# BARRELEYE_G2-FPDB_POST-PVT-X02-BOM-X05-20171123_Final.xls.xlsx — DEPOP (bom)
| FOXCONN TECHNOLOGY GROUP |  |  |  |  |  |  |  |  |  |  |  |  |
| BILL OF MATERIAL |  |  |  |  |  |  |  |  |  |  |  |  |
| REV OF  BOM | X05 | CUSTOMER | <name> |  | CUSTOMER P/N |  | PRODUCT CODE |  | PWA  REV | X02 | DATE | 43060 |
| Sourcing (Single/Sole/Multi) | Critical Commodity (Y or N) | Component Class (1, 2, other) | Customer PSL (Y or N) | Item Number | Foxconn P/N | Customer P/N | Part Description | Manufacturer  Full Name | Manufacturer  Part Number | Qty | RoHS Status | Location |
|  | Y |  | Y(1) | 1 | 620130V00-015-G |  | CAP,10uF,+/-20%,X6S,16V,G,SMD0603 | MURATA ELEC. NORTH AMERICA | GRM188C81C106MA73D | 6 |  | C23,C25,C27,C29,C31,C33 |
|  | ND | ND | Y(3) | 2 | 620103700-015-G | - | CAP,100nF,+/-10%,X7R,10V,G,SMD0402 | MURATA ELEC. NORTH AMERICA | GRM155R71A104K | 6 | Y | C24,C26,C28,C30,C32,C34 |
|  | Y | 2 | Y(3) | 3 | 620101T02-015-G | - | CAP,100nF,+/-10%,X7R,16V,G,SMD0402 | MURATA ELEC. NORTH AMERICA | GRM155R71C104K | 3 | Y | C71,C72,C2119 |
|  | Y | 2 | Y(1) | 4 | 620105400-015-G |  | CAP,1uF,+/-10%,X7R,16V,G,SMD0603 | MURATA ELEC. NORTH AMERICA | GRM188R71C105K | 1 | N | C401 |
|  | ND | ND | Y(1) | 5 | 62010P501-015-G | - | CAP,1nF,+/-10%,X7R,16V,G,SMD0402 | MURATA ELEC. NORTH AMERICA | GRM155R71C102KA01D | 1 | N | C2169 |
|  | ND |  | N | 6 | 52113DU00-289-G |  | LED,Hyper Red,LTS-2307CKD-P,G,5V,25mA,G,SMD-10 | LITE-ON TECHNOLOGY CORPORATION | LTS-2307CKD-P | 2 |  | LED1,LED2 |
|  | N | ND | Y(4) | 7 | 610107A00-017-G | - | RES,0 Ohm,+/-5%,1/16W,G,SMD0402 | KOA SPEER ELECTRONICS, INC. | RK73Z1ETTP | 20 | N | PSUR3,PEUR3,R5,PEUR5,R6,PHAR10,PSRR13,PHAR16,PHAR17,PHAR18,PHAR26,PHAR27,R1803,R1804,R1805,R1806,R1807,R1808,R1824,R1825 |
|  | ND | ND | Y(3) | 8 | 62010QB00-015-G | - | CAP,10nF,+/-10%,X7R,50V,G,SMD0402 | MURATA ELEC. NORTH AMERICA | GRM155R71H103K | 1 | N | PSRC9 |
|  | Y | 2 | Y(3) | 9 | 620105U00-015-G | - | CAP,220pF,+/-10%,X7R,50V,G,SMD0402 | MURATA ELEC. NORTH AMERICA | GRM155R71H221K | 1 | N | PSRC13 |
|  | ND | ND | Y(4) | 10 | 61011HA00-017-G |  | RES,1 Ohm,+/-1%,1/16W,G,SMD0402 | KOA SPEER ELECTRONICS, INC. | RK73H1ETTP1R00F | 1 | N | PSRR14 |
|  | ND |  | Y(4) | 11 | 61012JH00-017-G |  | RES,470 Ohm,+/-5%,1/8W,G,SMD0805 | KOA SPEER ELECTRONICS, INC. | RK73B2ATTD471J | 1 | N | PSRR20 |
|  | ND | ND | Y(4) | 12 | 61010LA00-017-G | - | RES,4.7KOhm,+/-1%,1/16W,G,SMD0402 | KOA SPEER ELECTRONICS, INC. | RK73H1ETTP4701F | 4 | N | R8,R53,R1776,R1777 |
|  | N | Other | Y(4) | 13 | 61010JY00-017-G | - | RES,220 Ohm,+/-5%,1/16W,G,SMD0402 | KOA SPEER ELECTRONICS, INC. | RK73B1ETTP221J | 18 | N | R16,R38,R252,R253,R254,R255,R256,R257,R258,R260,R261,R262,R263,R264,R265,R266,R267,R1774 |
|  | ND | ND | Y(4) | 14 | 61010L100-017-G | - | RES,100KOhm,+/-1%,1/16W,G,SMD0402 | KOA SPEER ELECTRONICS, INC. | RK73H1ETTP1003F | 1 | N | R24 |
|  | N | ND | Y(4) | 15 | 61010G500-017-G | - | RES,10KOhm,+/-1%,1/16W,G,SMD0402 | KOA SPEER ELECTRONICS, INC. | RK73H1ETTP1002F | 2 | N | R44,R1826 |
|  | N | ND | Y(4) | 16 | 610103300-017-G | - | RES,100KOhm,+/-5%,1/16W,G,SMD0402 | KOA SPEER ELECTRONICS, INC. | RK73B1ETTP104J | 18 | N | R58,R60,R62,R64,R66,R68,R72,R74,R76,R78,R80,R82,R86,R88,R90,R92,R94,R96 |
|  | ND | ND | Y(4) | 17 | 610103U00-017-G | - | RES,330 Ohm,+/-1%,1/10W,G,SMD0603 | KOA SPEER ELECTRONICS, INC. | RK73H1JTTD3300F | 12 | N | R63,R65,R67,R69,R77,R79,R81,R83,R91,R93,R95,R97 |
|  | N | other | Y(4) | 18 | 610107C00-017-G | K9577 | RES,10KOhm,+/-5%,1/16W,G,SMD0402 | KOA SPEER ELECTRONICS, INC. | RK73B1ETTP103J | 2 | N | R250,R259 |
|  | N | ND | Y(4) | 19 | 61010L300-017-G | - | RES,1KOhm,+/-1%,1/16W,G,SMD0402 | KOA SPEER ELECTRONICS, INC. | RK73H1ETTP1001F | 1 | N | R251 |
|  | N | Other | Y(4) | 20 | 61011MQ00-017-G | - | RES,4.75KOhm,+/-1%,1/16W,G,SMD0402 | KOA SPEER ELECTRONICS, INC. | RK73H1ETTP4751F | 2 | N | R1769,R1773 |
|  | N |  | Y(5) | 21 | 61100LR00-017-G |  | RES,100 Ohm,+/-1%,1/16W,G,SMD0402 | KOA SPEER ELECTRONICS, INC. | RN731ETTP1000F50 | 1 |  | R1778 |
|  | ND |  | N | 22 | 32022DM00-09N-G |  | IC,Power Controller,NCT7368S,G,SOP-8,SMD | Nuvoton Technology Corporation | NCT7368S | 6 |  | U9,U10,U11,U12,U13,U14 |
|  | ND | ND | Y(1) | 23 | 310200R00-183-G | - | IC,Trigger,SN74LV164ADBR,2~5.5V,G,SSOP-14,SMD | TEXAS INSTRUMENTS | SN74LV164ADBR | 2 | N | U25,U26 |
|  | ND |  | N | 24 | 3406ARH00-309-G |  | CONN,Header,Socket,V/T,Bla,2.54mm,10u,G,DIP-8 | SAMTEC INC. | ESQ-104-33-L-D | 1 |  | J10 |
